(kicad_pcb
	(version 20260206)
	(generator "pcbnew")
	(generator_version "10.0")
	(general
		(thickness 1.21888)
		(legacy_teardrops no)
	)
	(paper "A4")
	(title_block
		(title "timecard-v7 — TimeCard-DC-V7_EXP.PcbDoc")
		(comment 1 "Time Appliance Project (Time Card) / footprints 64-76 of 160")
	)
	(layers
		(0 "F.Cu" signal "TOP")
		(4 "In1.Cu" signal "SGND")
		(6 "In2.Cu" signal "IN1")
		(8 "In3.Cu" signal "IN2")
		(10 "In4.Cu" signal "SGND1")
		(2 "B.Cu" signal "BOTTOM")
		(9 "F.Adhes" user "F.Adhesive")
		(11 "B.Adhes" user "B.Adhesive")
		(13 "F.Paste" user "Top Paste")
		(15 "B.Paste" user "Bottom Paste")
		(5 "F.SilkS" user "Top Overlay")
		(7 "B.SilkS" user "Bottom Overlay")
		(1 "F.Mask" user "Top Solder")
		(3 "B.Mask" user "Bottom Solder")
		(17 "Dwgs.User" user "User.Drawings")
		(19 "Cmts.User" user "User.Comments")
		(21 "Eco1.User" user "User.Eco1")
		(23 "Eco2.User" user "User.Eco2")
		(25 "Edge.Cuts" user)
		(27 "Margin" user)
		(31 "F.CrtYd" user "Top Courtyard")
		(29 "B.CrtYd" user "Bottom Courtyard")
		(35 "F.Fab" user "Top Component Center")
		(33 "B.Fab" user "Bottom Component Center")
	)
	(footprint "Vault:FP-MK212BG-MFG"
		(layer "F.Cu")
		(at 94.3761 74.4286 -90)
		(property "Reference" "C58"
			(at 4.4 -0.843345 90)
			(unlocked yes)
			(layer "F.SilkS")
			(effects
				(font
					(size 0.762 0.762)
					(thickness 0.2286)
				)
				(justify left bottom)
			)
		)
		(property "Value" "10uF"
			(at 5.32679 1.5875 0)
			(unlocked yes)
			(layer "F.SilkS")
			(hide yes)
			(effects
				(font
					(size 1.524 1.524)
					(thickness 0.254)
				)
				(justify left bottom)
			)
		)
		(sheetname "GPS_IMU_SENSORS")
		(sheetfile "GPS_IMU_SENSORS.kicad_sch")
		(duplicate_pad_numbers_are_jumpers no)
		(fp_line
			(start 0.125 0.725)
			(end -0.125 0.725)
			(stroke
				(width 0.2)
				(type solid)
			)
			(layer "F.SilkS")
		)
		(fp_line
			(start 0.125 -0.725)
			(end -0.125 -0.725)
			(stroke
				(width 0.2)
				(type solid)
			)
			(layer "F.SilkS")
		)
		(fp_line
			(start -1.6 0.825)
			(end -1.6 -0.825)
			(stroke
				(width 0.2)
				(type solid)
			)
			(layer "F.CrtYd")
		)
		(fp_line
			(start 1.6 0.825)
			(end -1.6 0.825)
			(stroke
				(width 0.2)
				(type solid)
			)
			(layer "F.CrtYd")
		)
		(fp_line
			(start 1.6 0.825)
			(end 1.6 -0.825)
			(stroke
				(width 0.2)
				(type solid)
			)
			(layer "F.CrtYd")
		)
		(fp_line
			(start 1.6 -0.825)
			(end -1.6 -0.825)
			(stroke
				(width 0.2)
				(type solid)
			)
			(layer "F.CrtYd")
		)
		(fp_line
			(start -1.6 0.825)
			(end -1.6 -0.825)
			(stroke
				(width 0.2)
				(type solid)
			)
			(layer "F.Fab")
		)
		(fp_line
			(start 1.6 0.825)
			(end -1.6 0.825)
			(stroke
				(width 0.2)
				(type solid)
			)
			(layer "F.Fab")
		)
		(fp_line
			(start 1.6 0.825)
			(end 1.6 -0.825)
			(stroke
				(width 0.2)
				(type solid)
			)
			(layer "F.Fab")
		)
		(fp_line
			(start 0 0.5)
			(end 0 -0.5)
			(stroke
				(width 0.1)
				(type solid)
			)
			(layer "F.Fab")
		)
		(fp_line
			(start 0.5 0)
			(end -0.5 0)
			(stroke
				(width 0.1)
				(type solid)
			)
			(layer "F.Fab")
		)
		(fp_line
			(start 1.6 -0.825)
			(end -1.6 -0.825)
			(stroke
				(width 0.2)
				(type solid)
			)
			(layer "F.Fab")
		)
		(fp_text user "${REFERENCE}"
			(at -0.00001 0.09602 270)
			(unlocked yes)
			(layer "F.Fab")
			(effects
				(font
					(face "Arial")
					(size 0.63 0.63)
					(thickness 0.1)
				)
				(justify left bottom)
			)
		)
		(pad "1" smd rect
			(at -1 0 270)
			(size 1 1.25)
			(layers "F.Cu" "F.Mask" "F.Paste")
			(net "+3.3V")
			(solder_mask_margin 0)
			(solder_paste_margin 0)
		)
		(pad "2" smd rect
			(at 1 0 270)
			(size 1 1.25)
			(layers "F.Cu" "F.Mask" "F.Paste")
			(net "GND")
			(solder_mask_margin 0)
			(solder_paste_margin 0)
		)
	)
	(footprint "Vault:TECO-1909763-1_V"
		(layer "F.Cu")
		(at 74.3761 95.1162 -90)
		(property "Reference" "J1"
			(at -2.723079 1.271395 0)
			(unlocked yes)
			(layer "F.SilkS")
			(effects
				(font
					(size 0.762 0.762)
					(thickness 0.2286)
				)
			)
		)
		(property "Value" "1909763-1"
			(at 4.608085 3.749802 270)
			(unlocked yes)
			(layer "F.SilkS")
			(hide yes)
			(effects
				(font
					(size 1.524 1.524)
					(thickness 0.254)
				)
			)
		)
		(sheetname "USER_IO")
		(sheetfile "USER_IO.kicad_sch")
		(duplicate_pad_numbers_are_jumpers no)
		(fp_line
			(start 0.55 -1.3)
			(end -0.55 -1.3)
			(stroke
				(width 0.2)
				(type solid)
			)
			(layer "F.SilkS")
		)
		(fp_circle
			(center -1.778 1.65)
			(end -1.903 1.65)
			(stroke
				(width 0.25)
				(type solid)
			)
			(fill no)
			(layer "F.SilkS")
		)
		(pad "1" smd rect
			(at -1.475 0 270)
			(size 1.05 2.2)
			(layers "F.Cu" "F.Mask" "F.Paste")
			(net "GND")
		)
		(pad "2" smd rect
			(at 0 1.525 270)
			(size 1 1.05)
			(layers "F.Cu" "F.Mask" "F.Paste")
			(net "NetAN1_1")
		)
		(pad "3" smd rect
			(at 1.475 0 270)
			(size 1.05 2.2)
			(layers "F.Cu" "F.Mask" "F.Paste")
			(net "GND")
		)
	)
	(footprint "Capacitors:CAPC1608X10N"
		(layer "F.Cu")
		(at 202.4261 94.2162 -90)
		(property "Reference" "C3"
			(at -3.16 0.509345 270)
			(unlocked yes)
			(layer "F.SilkS")
			(effects
				(font
					(size 0.762 0.762)
					(thickness 0.2286)
				)
				(justify left bottom)
			)
		)
		(property "Value" "CAP_0603_0.01UF_50V"
			(at 0.91019 -8.8365 0)
			(unlocked yes)
			(layer "F.SilkS")
			(hide yes)
			(effects
				(font
					(size 1.524 1.524)
					(thickness 0.254)
				)
				(justify left bottom)
			)
		)
		(sheetname "POWER")
		(sheetfile "POWER.kicad_sch")
		(duplicate_pad_numbers_are_jumpers no)
		(fp_line
			(start 0.635 0.7112)
			(end -0.635 0.7112)
			(stroke
				(width 0.1524)
				(type solid)
			)
			(layer "F.SilkS")
		)
		(fp_line
			(start 0.635 -0.7112)
			(end -0.635 -0.7112)
			(stroke
				(width 0.1524)
				(type solid)
			)
			(layer "F.SilkS")
		)
		(pad "1" smd rect
			(at -0.8 0)
			(size 0.95 1)
			(layers "F.Cu" "F.Mask" "F.Paste")
			(net "NetC3_1")
		)
		(pad "2" smd rect
			(at 0.8 0)
			(size 0.95 1)
			(layers "F.Cu" "F.Mask" "F.Paste")
			(net "NetC3_2")
		)
	)
	(footprint "Vault:AMPH-901-143-6RFX_V"
		(layer "F.Cu")
		(at 60.9761 95.0786 180)
		(property "Reference" "AN1"
			(at -5.993345 2.7124 90)
			(unlocked yes)
			(layer "F.SilkS")
			(effects
				(font
					(size 0.762 0.762)
					(thickness 0.2286)
				)
				(justify left bottom)
			)
		)
		(property "Value" "901-143-6RFX"
			(at 4.6101 -12.21359 0)
			(unlocked yes)
			(layer "F.SilkS")
			(hide yes)
			(effects
				(font
					(size 1.524 1.524)
					(thickness 0.254)
				)
				(justify left bottom)
			)
		)
		(sheetname "USER_IO")
		(sheetfile "USER_IO.kicad_sch")
		(duplicate_pad_numbers_are_jumpers no)
		(fp_line
			(start 3.5 -1.38)
			(end 3.5 1.38)
			(stroke
				(width 0.2)
				(type solid)
			)
			(layer "F.SilkS")
		)
		(fp_line
			(start 1.38 3.5)
			(end -1.38 3.5)
			(stroke
				(width 0.2)
				(type solid)
			)
			(layer "F.SilkS")
		)
		(fp_line
			(start 1.38 -3.5)
			(end -1.38 -3.5)
			(stroke
				(width 0.2)
				(type solid)
			)
			(layer "F.SilkS")
		)
		(fp_line
			(start -3.5 -1.38)
			(end -3.5 1.38)
			(stroke
				(width 0.2)
				(type solid)
			)
			(layer "F.SilkS")
		)
		(pad "1" thru_hole rect
			(at 0 0 180)
			(size 2 2)
			(drill 1.5)
			(layers "*.Cu" "*.Mask")
			(remove_unused_layers no)
			(net "NetAN1_1")
		)
		(pad "2" thru_hole circle
			(at -2.54 -2.54 180)
			(size 2.2 2.2)
			(drill 1.7)
			(layers "*.Cu" "*.Mask")
			(remove_unused_layers no)
			(net "GND")
			(thermal_bridge_angle 90)
		)
		(pad "3" thru_hole circle
			(at -2.54 2.54 180)
			(size 2.2 2.2)
			(drill 1.7)
			(layers "*.Cu" "*.Mask")
			(remove_unused_layers no)
			(net "GND")
			(thermal_bridge_angle 90)
		)
		(pad "4" thru_hole circle
			(at 2.54 2.54 180)
			(size 2.2 2.2)
			(drill 1.7)
			(layers "*.Cu" "*.Mask")
			(remove_unused_layers no)
			(net "GND")
			(thermal_bridge_angle 90)
		)
		(pad "5" thru_hole circle
			(at 2.54 -2.54 180)
			(size 2.2 2.2)
			(drill 1.7)
			(layers "*.Cu" "*.Mask")
			(remove_unused_layers no)
			(net "GND")
			(thermal_bridge_angle 90)
		)
	)
	(footprint "Vault:RESC3116X65X50ML20T20"
		(layer "F.Cu")
		(at 149.9261 86.8162 180)
		(property "Reference" "R46"
			(at 1.5714 2.173079 0)
			(unlocked yes)
			(layer "F.SilkS")
			(effects
				(font
					(size 0.762 0.762)
					(thickness 0.2286)
				)
			)
		)
		(property "Value" "DNI_0_5%_1206"
			(at 7.29942 3.318002 180)
			(unlocked yes)
			(layer "F.SilkS")
			(hide yes)
			(effects
				(font
					(size 1.524 1.524)
					(thickness 0.254)
				)
			)
		)
		(sheetname "MAC")
		(sheetfile "MAC.kicad_sch")
		(duplicate_pad_numbers_are_jumpers no)
		(fp_line
			(start 0.35 0.85)
			(end -0.35 0.85)
			(stroke
				(width 0.2)
				(type solid)
			)
			(layer "F.SilkS")
		)
		(fp_line
			(start 0.35 -0.85)
			(end -0.35 -0.85)
			(stroke
				(width 0.2)
				(type solid)
			)
			(layer "F.SilkS")
		)
		(pad "1" smd rect
			(at -1.475 0 270)
			(size 1.9 1.45)
			(layers "F.Cu" "F.Mask" "F.Paste")
			(net "MAC_VCC")
		)
		(pad "2" smd rect
			(at 1.475 0 270)
			(size 1.9 1.45)
			(layers "F.Cu" "F.Mask" "F.Paste")
			(net "+12V")
		)
	)
	(footprint "Vault:CAPC1608X87X45ML20T05"
		(layer "F.Cu")
		(at 201.5087 84.9372 -90)
		(property "Reference" "C21"
			(at -4.371 0.538345 270)
			(unlocked yes)
			(layer "F.SilkS")
			(effects
				(font
					(size 0.762 0.762)
					(thickness 0.2286)
				)
				(justify left bottom)
			)
		)
		(property "Value" "0.1uF"
			(at 7.13319 -20.1395 0)
			(unlocked yes)
			(layer "F.SilkS")
			(hide yes)
			(effects
				(font
					(size 1.524 1.524)
					(thickness 0.254)
				)
				(justify left bottom)
			)
		)
		(sheetname "POWER")
		(sheetfile "POWER.kicad_sch")
		(duplicate_pad_numbers_are_jumpers no)
		(pad "1" smd rect
			(at -0.7 0)
			(size 1.1 1.05)
			(layers "F.Cu" "F.Mask" "F.Paste")
			(net "GND")
		)
		(pad "2" smd rect
			(at 0.7 0)
			(size 1.1 1.05)
			(layers "F.Cu" "F.Mask" "F.Paste")
			(net "NetC21_2")
		)
	)
	(footprint "Vault:RESC1608X55X30NL15T15"
		(layer "F.Cu")
		(at 84.1261 139.6162 -90)
		(property "Reference" "R31"
			(at 2.771395 -0.026921 90)
			(unlocked yes)
			(layer "F.SilkS")
			(effects
				(font
					(size 0.762 0.762)
					(thickness 0.2286)
				)
			)
		)
		(property "Value" "4.7K"
			(at 1.63744 2.352802 270)
			(unlocked yes)
			(layer "F.SilkS")
			(hide yes)
			(effects
				(font
					(size 1.524 1.524)
					(thickness 0.254)
				)
			)
		)
		(sheetname "USER_IO")
		(sheetfile "USER_IO.kicad_sch")
		(duplicate_pad_numbers_are_jumpers no)
		(pad "1" smd rect
			(at -0.75 0)
			(size 0.95 0.95)
			(layers "F.Cu" "F.Mask" "F.Paste")
			(net "ANT4_IO_OUT")
		)
		(pad "2" smd rect
			(at 0.75 0)
			(size 0.95 0.95)
			(layers "F.Cu" "F.Mask" "F.Paste")
			(net "+3.3V")
		)
	)
	(footprint "Vault:RESC1608X55X25LL10T15"
		(layer "F.Cu")
		(at 130.3761 87.3286)
		(property "Reference" "R11"
			(at -1.821395 0.014521 0)
			(unlocked yes)
			(layer "F.SilkS")
			(effects
				(font
					(size 0.762 0.762)
					(thickness 0.2286)
				)
			)
		)
		(property "Value" "4.7K"
			(at -2.657602 2.60264 270)
			(unlocked yes)
			(layer "F.SilkS")
			(hide yes)
			(effects
				(font
					(size 1.524 1.524)
					(thickness 0.254)
				)
			)
		)
		(sheetname "MAC")
		(sheetfile "MAC.kicad_sch")
		(duplicate_pad_numbers_are_jumpers no)
		(pad "1" smd rect
			(at -0.65 0 90)
			(size 0.8 0.6)
			(layers "F.Cu" "F.Mask" "F.Paste")
			(net "GND")
		)
		(pad "2" smd rect
			(at 0.65 0 90)
			(size 0.8 0.6)
			(layers "F.Cu" "F.Mask" "F.Paste")
			(net "FPGA_MAC_PPS_IN0-")
		)
	)
	(footprint "SamacSys:155124M173200"
		(layer "F.Cu")
		(at 58.4511 82.6662 90)
		(property "Reference" "D14"
			(at -4.7 -0.231655 90)
			(unlocked yes)
			(layer "F.SilkS")
			(effects
				(font
					(size 0.762 0.762)
					(thickness 0.2286)
				)
				(justify left bottom)
			)
		)
		(property "Value" "155124M173200"
			(at -4.13639 -0.5715 0)
			(unlocked yes)
			(layer "F.SilkS")
			(hide yes)
			(effects
				(font
					(size 1.524 1.524)
					(thickness 0.254)
				)
				(justify left bottom)
			)
		)
		(sheetname "USER_IO_STATUS")
		(sheetfile "USER_IO_STATUS.kicad_sch")
		(duplicate_pad_numbers_are_jumpers no)
		(fp_line
			(start -0.8 0.5)
			(end 0.8 0.5)
			(stroke
				(width 0.1)
				(type solid)
			)
			(layer "F.SilkS")
		)
		(fp_arc
			(start -2 -0.1)
			(mid -1.95 -0.05)
			(end -2 0)
			(stroke
				(width 0.1)
				(type solid)
			)
			(layer "F.SilkS")
		)
		(fp_arc
			(start -2 0)
			(mid -2.05 -0.05)
			(end -2 -0.1)
			(stroke
				(width 0.1)
				(type solid)
			)
			(layer "F.SilkS")
		)
		(pad "1" smd rect
			(at -1.4 0 180)
			(size 0.9 0.6)
			(layers "F.Cu" "F.Mask" "F.Paste")
			(net "+3.3V")
		)
		(pad "2" smd rect
			(at -0.45 -0.325 90)
			(size 0.6 0.55)
			(layers "F.Cu" "F.Mask" "F.Paste")
			(net "NetD14_2")
		)
		(pad "3" smd rect
			(at 0.45 -0.325 90)
			(size 0.6 0.55)
			(layers "F.Cu" "F.Mask" "F.Paste")
			(net "NetD14_3")
		)
		(pad "4" smd rect
			(at 1.4 0 180)
			(size 0.9 0.6)
			(layers "F.Cu" "F.Mask" "F.Paste")
			(net "NetD14_4")
		)
	)
	(footprint "Capacitors:CAPC2012X14N"
		(layer "F.Cu")
		(at 221.3637 88.7662)
		(property "Reference" "C7"
			(at 3 0.393345 0)
			(unlocked yes)
			(layer "F.SilkS")
			(effects
				(font
					(size 0.762 0.762)
					(thickness 0.2286)
				)
				(justify left bottom)
			)
		)
		(property "Value" "CAP_0805_10UF_25V"
			(at -4.8911 19.63119 0)
			(unlocked yes)
			(layer "F.SilkS")
			(hide yes)
			(effects
				(font
					(size 1.524 1.524)
					(thickness 0.254)
				)
				(justify left bottom)
			)
		)
		(sheetname "POWER")
		(sheetfile "POWER.kicad_sch")
		(duplicate_pad_numbers_are_jumpers no)
		(fp_line
			(start -0.762 -0.9652)
			(end 0.762 -0.9652)
			(stroke
				(width 0.1524)
				(type solid)
			)
			(layer "F.SilkS")
		)
		(fp_line
			(start -0.762 0.9652)
			(end 0.762 0.9652)
			(stroke
				(width 0.1524)
				(type solid)
			)
			(layer "F.SilkS")
		)
		(pad "1" smd rect
			(at -0.9 0 90)
			(size 1.45 1.15)
			(layers "F.Cu" "F.Mask" "F.Paste")
			(net "+3.3V")
		)
		(pad "2" smd rect
			(at 0.9 0 90)
			(size 1.45 1.15)
			(layers "F.Cu" "F.Mask" "F.Paste")
			(net "GND")
		)
	)
	(footprint "Vault:FP-LTST-C191TBKT-MFG"
		(layer "F.Cu")
		(at 73.3761 52.1162 90)
		(property "Reference" "D10"
			(at -6.5214 0.026921 90)
			(unlocked yes)
			(layer "F.SilkS")
			(effects
				(font
					(size 0.762 0.762)
					(thickness 0.2286)
				)
			)
		)
		(property "Value" "BLUE"
			(at 1.307195 2.479802 90)
			(unlocked yes)
			(layer "F.SilkS")
			(hide yes)
			(effects
				(font
					(size 1.524 1.524)
					(thickness 0.254)
				)
			)
		)
		(sheetname "USER_IO_STATUS")
		(sheetfile "USER_IO_STATUS.kicad_sch")
		(duplicate_pad_numbers_are_jumpers no)
		(fp_line
			(start -0.85 -0.8)
			(end 0.85 -0.8)
			(stroke
				(width 0.2)
				(type solid)
			)
			(layer "F.SilkS")
		)
		(fp_line
			(start -0.85 0.8)
			(end 0.85 0.8)
			(stroke
				(width 0.2)
				(type solid)
			)
			(layer "F.SilkS")
		)
		(fp_circle
			(center -1.75 0)
			(end -1.625 0)
			(stroke
				(width 0.25)
				(type solid)
			)
			(fill no)
			(layer "F.SilkS")
		)
		(fp_line
			(start 1.25 -0.55)
			(end 1.25 0.55)
			(stroke
				(width 0.2)
				(type solid)
			)
			(layer "F.CrtYd")
		)
		(fp_line
			(start -1.25 -0.55)
			(end 1.25 -0.55)
			(stroke
				(width 0.2)
				(type solid)
			)
			(layer "F.CrtYd")
		)
		(fp_line
			(start -1.25 -0.55)
			(end -1.25 0.55)
			(stroke
				(width 0.2)
				(type solid)
			)
			(layer "F.CrtYd")
		)
		(fp_line
			(start -1.25 0.55)
			(end 1.25 0.55)
			(stroke
				(width 0.2)
				(type solid)
			)
			(layer "F.CrtYd")
		)
		(fp_line
			(start 1.25 -0.55)
			(end 1.25 0.55)
			(stroke
				(width 0.2)
				(type solid)
			)
			(layer "F.Fab")
		)
		(fp_line
			(start -1.25 -0.55)
			(end 1.25 -0.55)
			(stroke
				(width 0.2)
				(type solid)
			)
			(layer "F.Fab")
		)
		(fp_line
			(start -1.25 -0.55)
			(end -1.25 0.55)
			(stroke
				(width 0.2)
				(type solid)
			)
			(layer "F.Fab")
		)
		(fp_line
			(start 0 -0.5)
			(end 0 0.5)
			(stroke
				(width 0.1)
				(type solid)
			)
			(layer "F.Fab")
		)
		(fp_line
			(start -0.5 0)
			(end 0.5 0)
			(stroke
				(width 0.1)
				(type solid)
			)
			(layer "F.Fab")
		)
		(fp_line
			(start -1.25 0.55)
			(end 1.25 0.55)
			(stroke
				(width 0.2)
				(type solid)
			)
			(layer "F.Fab")
		)
		(pad "1" smd rect
			(at -0.75 0 90)
			(size 0.8 0.8)
			(layers "F.Cu" "F.Mask" "F.Paste")
			(net "NetD10_1")
			(solder_mask_margin 0)
			(solder_paste_margin 0)
		)
		(pad "2" smd rect
			(at 0.75 0 90)
			(size 0.8 0.8)
			(layers "F.Cu" "F.Mask" "F.Paste")
			(net "+3.3V")
			(solder_mask_margin 0)
			(solder_paste_margin 0)
		)
	)
	(footprint "Resistors:RESC1005X04N"
		(layer "F.Cu")
		(at 133.4761 145.5786 -90)
		(property "Reference" "R24"
			(at 1.35111 0.884735 90)
			(unlocked yes)
			(layer "F.SilkS")
			(effects
				(font
					(size 0.762 0.762)
					(thickness 0.2286)
				)
				(justify left bottom)
			)
		)
		(property "Value" "ERJ-2GE0R00X"
			(at 3.42519 0.2413 0)
			(unlocked yes)
			(layer "F.SilkS")
			(hide yes)
			(effects
				(font
					(size 1.524 1.524)
					(thickness 0.254)
				)
				(justify left bottom)
			)
		)
		(sheetname "PCIe_JTAG")
		(sheetfile "PCIe_JTAG.kicad_sch")
		(duplicate_pad_numbers_are_jumpers no)
		(pad "1" smd rect
			(at -0.425 0)
			(size 0.6 0.65)
			(layers "F.Cu" "F.Mask" "F.Paste")
			(net "PRSNT")
		)
		(pad "2" smd rect
			(at 0.425 0)
			(size 0.6 0.65)
			(layers "F.Cu" "F.Mask" "F.Paste")
			(net "NetP2_B31")
		)
	)
	(footprint "Vault:TECO-1909763-1_V"
		(layer "F.Cu")
		(at 74.3761 108.6162 -90)
		(property "Reference" "J2"
			(at -2.973079 1.271395 0)
			(unlocked yes)
			(layer "F.SilkS")
			(effects
				(font
					(size 0.762 0.762)
					(thickness 0.2286)
				)
			)
		)
		(property "Value" "1909763-1"
			(at 4.608085 3.749802 270)
			(unlocked yes)
			(layer "F.SilkS")
			(hide yes)
			(effects
				(font
					(size 1.524 1.524)
					(thickness 0.254)
				)
			)
		)
		(sheetname "USER_IO")
		(sheetfile "USER_IO.kicad_sch")
		(duplicate_pad_numbers_are_jumpers no)
		(fp_line
			(start 0.55 -1.3)
			(end -0.55 -1.3)
			(stroke
				(width 0.2)
				(type solid)
			)
			(layer "F.SilkS")
		)
		(fp_circle
			(center -1.778 1.65)
			(end -1.903 1.65)
			(stroke
				(width 0.25)
				(type solid)
			)
			(fill no)
			(layer "F.SilkS")
		)
		(pad "1" smd rect
			(at -1.475 0 270)
			(size 1.05 2.2)
			(layers "F.Cu" "F.Mask" "F.Paste")
			(net "GND")
		)
		(pad "2" smd rect
			(at 0 1.525 270)
			(size 1 1.05)
			(layers "F.Cu" "F.Mask" "F.Paste")
			(net "NetAN2_1")
		)
		(pad "3" smd rect
			(at 1.475 0 270)
			(size 1.05 2.2)
			(layers "F.Cu" "F.Mask" "F.Paste")
			(net "GND")
		)
	)
)
